(kicad_pcb
	(version 20260206)
	(generator "pcbnew")
	(generator_version "10.0")
	(general
		(thickness 1.6)
		(legacy_teardrops no)
	)
	(paper "A4")
	(title_block
		(title "ptb — 12523-1.1018WZS1506.brd")
		(comment 1 "Open Vault / Knox (Wiwynn) / footprints 4-11 of 61")
	)
	(layers
		(0 "F.Cu" signal "TOP")
		(4 "In1.Cu" signal "L2GND")
		(6 "In2.Cu" signal "L3VCC")
		(2 "B.Cu" signal "BOTTOM")
		(9 "F.Adhes" user "F.Adhesive")
		(11 "B.Adhes" user "B.Adhesive")
		(13 "F.Paste" user "Package Geometry/Pastemask Top")
		(15 "B.Paste" user "Package Geometry/Pastemask Bottom")
		(5 "F.SilkS" user "Ref Des/Silkscreen Top")
		(7 "B.SilkS" user "Ref Des/Silkscreen Bottom")
		(1 "F.Mask" user "Board Geometry/Soldermask Top")
		(3 "B.Mask" user "Board Geometry/Soldermask Bottom")
		(17 "Dwgs.User" user "User.Drawings")
		(19 "Cmts.User" user "User.Comments")
		(21 "Eco1.User" user "User.Eco1")
		(23 "Eco2.User" user "User.Eco2")
		(25 "Edge.Cuts" user "Board Geometry/Outline")
		(27 "Margin" user)
		(31 "F.CrtYd" user "Package Geometry/Place Bound Top")
		(29 "B.CrtYd" user "Package Geometry/Place Bound Bottom")
		(35 "F.Fab" user "Ref Des/Assembly Top")
		(33 "B.Fab" user "Ref Des/Assembly Bottom")
	)
	(footprint ""
		(layer "F.Cu")
		(at 126.659894 -5.999988)
		(property "Reference" "H4"
			(at 0 0 0)
			(layer "F.SilkS")
			(hide yes)
			(effects
				(font
					(size 1.27 1.27)
				)
			)
		)
		(property "Value" "HOLET827X355B355R158-S"
			(at -18.200878 0.089916 0)
			(unlocked yes)
			(layer "F.Fab")
			(hide yes)
			(effects
				(font
					(size 1.016 1.016)
					(thickness 0.1524)
				)
			)
		)
		(property "Device Type" "HOLET827X355B355R158-S"
			(at -18.200878 -1.434084 0)
			(unlocked yes)
			(layer "F.Fab")
			(hide yes)
			(effects
				(font
					(size 1.016 1.016)
					(thickness 0.1524)
				)
			)
		)
		(duplicate_pad_numbers_are_jumpers no)
		(fp_poly
			(pts
				(arc
					(start -4.8133 0)
					(mid 4.8133 0)
					(end -4.8133 0)
				)
			)
			(stroke
				(width 0)
				(type default)
			)
			(fill no)
			(layer "B.CrtYd")
		)
		(fp_poly
			(pts
				(arc
					(start -11.9888 4.8133)
					(mid -16.8021 0)
					(end -11.9888 -4.8133)
				)
				(arc
					(start 0 -4.8133)
					(mid 4.8133 0)
					(end 0 4.8133)
				)
			)
			(stroke
				(width 0)
				(type default)
			)
			(fill no)
			(layer "F.CrtYd")
		)
		(fp_poly
			(pts
				(arc
					(start -4.8133 0)
					(mid 4.8133 0)
					(end -4.8133 0)
				)
			)
			(stroke
				(width 0)
				(type default)
			)
			(fill no)
			(layer "B.Fab")
		)
		(fp_poly
			(pts
				(arc
					(start -11.9888 4.8133)
					(mid -16.8021 0)
					(end -11.9888 -4.8133)
				)
				(arc
					(start 0 -4.8133)
					(mid 4.8133 0)
					(end 0 4.8133)
				)
			)
			(stroke
				(width 0)
				(type default)
			)
			(fill no)
			(layer "F.Fab")
		)
		(pad "1" thru_hole oval
			(at 0 0)
			(size 21.0058 9.017)
			(drill 4.0132
				(offset -5.9944 0)
			)
			(layers "*.Cu" "*.Mask")
			(remove_unused_layers no)
			(net "GND")
			(clearance -7.9883)
			(thermal_gap 0.3048)
			(padstack
				(mode front_inner_back)
				(layer "Inner"
					(shape circle)
					(size 4.4196 4.4196)
					(clearance 0.3048)
				)
				(layer "B.Cu"
					(shape circle)
					(size 9.017 9.017)
					(clearance -1.9939)
				)
			)
		)
	)
	(footprint ""
		(layer "F.Cu")
		(at 9.684512 -95.791528 180)
		(property "Reference" "C357"
			(at 0 0 180)
			(layer "F.SilkS")
			(hide yes)
			(effects
				(font
					(size 1.27 1.27)
				)
			)
		)
		(property "Value" "SC220P50V3JN-GP"
			(at 0 -2.8194 180)
			(unlocked yes)
			(layer "F.Fab")
			(hide yes)
			(effects
				(font
					(size 1.016 1.016)
					(thickness 0.1524)
				)
			)
		)
		(property "Device Type" "C603H36"
			(at 0 -4.3434 180)
			(unlocked yes)
			(layer "F.Fab")
			(hide yes)
			(effects
				(font
					(size 1.016 1.016)
					(thickness 0.1524)
				)
			)
		)
		(duplicate_pad_numbers_are_jumpers no)
		(fp_line
			(start 0.508 0)
			(end -0.508 0)
			(stroke
				(width 0.2032)
				(type default)
			)
			(layer "F.SilkS")
		)
		(fp_rect
			(start -0.5842 1.3335)
			(end 0.5842 -1.3335)
			(stroke
				(width 0)
				(type default)
			)
			(fill no)
			(layer "F.CrtYd")
		)
		(fp_rect
			(start -0.5842 1.3335)
			(end 0.5842 -1.3335)
			(stroke
				(width 0)
				(type default)
			)
			(fill no)
			(layer "F.Fab")
		)
		(pad "1" smd custom
			(at 0 -0.762 180)
			(size 0.2159 0.2159)
			(layers "F.Cu" "F.Mask" "F.Paste")
			(net "I2C_C_SDA")
			(options
				(clearance outline)
				(anchor circle)
			)
			(primitives
				(gr_poly
					(pts
						(arc
							(start -0.3302 -0.4318)
							(mid -0.402042 -0.402042)
							(end -0.4318 -0.3302)
						)
						(arc
							(start -0.4318 0.3302)
							(mid -0.402042 0.402042)
							(end -0.3302 0.4318)
						)
						(arc
							(start 0.3302 0.4318)
							(mid 0.402042 0.402042)
							(end 0.4318 0.3302)
						)
						(arc
							(start 0.4318 -0.3302)
							(mid 0.402042 -0.402042)
							(end 0.3302 -0.4318)
						)
					)
					(width 0)
					(fill yes)
				)
			)
		)
		(pad "2" smd custom
			(at 0 0.762 180)
			(size 0.2159 0.2159)
			(layers "F.Cu" "F.Mask" "F.Paste")
			(net "GND")
			(options
				(clearance outline)
				(anchor circle)
			)
			(primitives
				(gr_poly
					(pts
						(arc
							(start -0.3302 -0.4318)
							(mid -0.402042 -0.402042)
							(end -0.4318 -0.3302)
						)
						(arc
							(start -0.4318 0.3302)
							(mid -0.402042 0.402042)
							(end -0.3302 0.4318)
						)
						(arc
							(start 0.3302 0.4318)
							(mid 0.402042 0.402042)
							(end 0.4318 0.3302)
						)
						(arc
							(start 0.4318 -0.3302)
							(mid 0.402042 -0.402042)
							(end 0.3302 -0.4318)
						)
					)
					(width 0)
					(fill yes)
				)
			)
		)
	)
	(footprint ""
		(layer "F.Cu")
		(at 137.795 -66.286634)
		(property "Reference" "C359"
			(at 0 0 0)
			(layer "F.SilkS")
			(hide yes)
			(effects
				(font
					(size 1.27 1.27)
				)
			)
		)
		(property "Value" "SC220P50V3JN-GP"
			(at 0 -2.8194 0)
			(unlocked yes)
			(layer "F.Fab")
			(hide yes)
			(effects
				(font
					(size 1.016 1.016)
					(thickness 0.1524)
				)
			)
		)
		(property "Device Type" "C603H36"
			(at 0 -4.3434 0)
			(unlocked yes)
			(layer "F.Fab")
			(hide yes)
			(effects
				(font
					(size 1.016 1.016)
					(thickness 0.1524)
				)
			)
		)
		(duplicate_pad_numbers_are_jumpers no)
		(fp_line
			(start 0.508 0)
			(end -0.508 0)
			(stroke
				(width 0.2032)
				(type default)
			)
			(layer "F.SilkS")
		)
		(fp_rect
			(start -0.5842 1.3335)
			(end 0.5842 -1.3335)
			(stroke
				(width 0)
				(type default)
			)
			(fill no)
			(layer "F.CrtYd")
		)
		(fp_rect
			(start -0.5842 1.3335)
			(end 0.5842 -1.3335)
			(stroke
				(width 0)
				(type default)
			)
			(fill no)
			(layer "F.Fab")
		)
		(pad "1" smd custom
			(at 0 -0.762)
			(size 0.2159 0.2159)
			(layers "F.Cu" "F.Mask" "F.Paste")
			(net "I2C_C_BUF_SCL_CONN")
			(options
				(clearance outline)
				(anchor circle)
			)
			(primitives
				(gr_poly
					(pts
						(arc
							(start -0.3302 -0.4318)
							(mid -0.402042 -0.402042)
							(end -0.4318 -0.3302)
						)
						(arc
							(start -0.4318 0.3302)
							(mid -0.402042 0.402042)
							(end -0.3302 0.4318)
						)
						(arc
							(start 0.3302 0.4318)
							(mid 0.402042 0.402042)
							(end 0.4318 0.3302)
						)
						(arc
							(start 0.4318 -0.3302)
							(mid 0.402042 -0.402042)
							(end 0.3302 -0.4318)
						)
					)
					(width 0)
					(fill yes)
				)
			)
		)
		(pad "2" smd custom
			(at 0 0.762)
			(size 0.2159 0.2159)
			(layers "F.Cu" "F.Mask" "F.Paste")
			(net "GND")
			(options
				(clearance outline)
				(anchor circle)
			)
			(primitives
				(gr_poly
					(pts
						(arc
							(start -0.3302 -0.4318)
							(mid -0.402042 -0.402042)
							(end -0.4318 -0.3302)
						)
						(arc
							(start -0.4318 0.3302)
							(mid -0.402042 0.402042)
							(end -0.3302 0.4318)
						)
						(arc
							(start 0.3302 0.4318)
							(mid 0.402042 0.402042)
							(end 0.4318 0.3302)
						)
						(arc
							(start 0.4318 -0.3302)
							(mid 0.402042 -0.402042)
							(end 0.3302 -0.4318)
						)
					)
					(width 0)
					(fill yes)
				)
			)
		)
	)
	(footprint ""
		(layer "F.Cu")
		(at 139.826492 -82.838544)
		(property "Reference" "R378"
			(at 0 0 0)
			(layer "F.SilkS")
			(hide yes)
			(effects
				(font
					(size 1.27 1.27)
				)
			)
		)
		(property "Value" "68R5J-GP"
			(at 0 -8.9535 0)
			(unlocked yes)
			(layer "F.Fab")
			(hide yes)
			(effects
				(font
					(size 1.27 1.016)
					(thickness 0.1524)
				)
			)
		)
		(property "Device Type" "R805H24"
			(at 0 -10.6299 0)
			(unlocked yes)
			(layer "F.Fab")
			(hide yes)
			(effects
				(font
					(size 1.27 1.016)
					(thickness 0.1524)
				)
			)
		)
		(duplicate_pad_numbers_are_jumpers no)
		(fp_line
			(start -0.889 -1.7018)
			(end -0.889 0.2794)
			(stroke
				(width 0.1524)
				(type default)
			)
			(layer "F.SilkS")
		)
		(fp_line
			(start -0.889 0.0762)
			(end -0.889 1.7018)
			(stroke
				(width 0.1524)
				(type default)
			)
			(layer "F.SilkS")
		)
		(fp_line
			(start -0.889 1.7018)
			(end 0.889 1.7018)
			(stroke
				(width 0.1524)
				(type default)
			)
			(layer "F.SilkS")
		)
		(fp_line
			(start 0.889 -1.7018)
			(end -0.889 -1.7018)
			(stroke
				(width 0.1524)
				(type default)
			)
			(layer "F.SilkS")
		)
		(fp_line
			(start 0.889 -1.7018)
			(end 0.889 -0.381)
			(stroke
				(width 0.1524)
				(type default)
			)
			(layer "F.SilkS")
		)
		(fp_line
			(start 0.889 1.7018)
			(end 0.889 -0.508)
			(stroke
				(width 0.1524)
				(type default)
			)
			(layer "F.SilkS")
		)
		(fp_poly
			(pts
				(xy 0.9652 -1.778) (xy 0.9652 1.778) (xy -0.9652 1.778) (xy -0.9652 -1.778)
			)
			(stroke
				(width 0)
				(type default)
			)
			(fill no)
			(layer "F.CrtYd")
		)
		(fp_rect
			(start -0.9652 1.778)
			(end 0.9652 -1.778)
			(stroke
				(width 0)
				(type default)
			)
			(fill no)
			(layer "F.Fab")
		)
		(pad "1" smd rect
			(at 0 -0.9652)
			(size 1.397 1.143)
			(layers "F.Cu" "F.Mask" "F.Paste")
			(net "EMITTER_K")
		)
		(pad "2" smd rect
			(at 0 0.9652)
			(size 1.397 1.143)
			(layers "F.Cu" "F.Mask" "F.Paste")
			(net "GND")
		)
	)
	(footprint ""
		(layer "F.Cu")
		(at 12.977876 -98.81235)
		(property "Reference" "R344"
			(at 0 0 0)
			(layer "F.SilkS")
			(hide yes)
			(effects
				(font
					(size 1.27 1.27)
				)
			)
		)
		(property "Value" "10KR2F-2-GP"
			(at 0.064008 -3.993896 0)
			(unlocked yes)
			(layer "F.Fab")
			(hide yes)
			(effects
				(font
					(size 1.016 1.016)
					(thickness 0.1524)
				)
			)
		)
		(property "Device Type" "R402H16"
			(at 0.064008 -5.517896 0)
			(unlocked yes)
			(layer "F.Fab")
			(hide yes)
			(effects
				(font
					(size 1.016 1.016)
					(thickness 0.1524)
				)
			)
		)
		(duplicate_pad_numbers_are_jumpers no)
		(fp_line
			(start -0.508 -0.9398)
			(end -0.508 0.9398)
			(stroke
				(width 0.1524)
				(type default)
			)
			(layer "F.SilkS")
		)
		(fp_line
			(start 0.508 -0.9398)
			(end -0.508 -0.9398)
			(stroke
				(width 0.1524)
				(type default)
			)
			(layer "F.SilkS")
		)
		(fp_rect
			(start -0.508 0.9398)
			(end 0.508 -0.9398)
			(stroke
				(width 0)
				(type default)
			)
			(fill no)
			(layer "F.CrtYd")
		)
		(fp_rect
			(start -0.508 0.9398)
			(end 0.508 -0.9398)
			(stroke
				(width 0)
				(type default)
			)
			(fill no)
			(layer "F.Fab")
		)
		(pad "1" smd custom
			(at 0 -0.4445)
			(size 0.1397 0.1397)
			(layers "F.Cu" "F.Mask" "F.Paste")
			(net "P3V3")
			(options
				(clearance outline)
				(anchor circle)
			)
			(primitives
				(gr_poly
					(pts
						(arc
							(start -0.1778 -0.2794)
							(mid -0.249642 -0.249642)
							(end -0.2794 -0.1778)
						)
						(arc
							(start -0.2794 0.1778)
							(mid -0.249642 0.249642)
							(end -0.1778 0.2794)
						)
						(arc
							(start 0.1778 0.2794)
							(mid 0.249642 0.249642)
							(end 0.2794 0.1778)
						)
						(arc
							(start 0.2794 -0.1778)
							(mid 0.249642 -0.249642)
							(end 0.1778 -0.2794)
						)
					)
					(width 0)
					(fill yes)
				)
			)
		)
		(pad "2" smd custom
			(at 0 0.4445)
			(size 0.1397 0.1397)
			(layers "F.Cu" "F.Mask" "F.Paste")
			(net "I2C_C_BUF_SDAOUT")
			(options
				(clearance outline)
				(anchor circle)
			)
			(primitives
				(gr_poly
					(pts
						(arc
							(start -0.1778 -0.2794)
							(mid -0.249642 -0.249642)
							(end -0.2794 -0.1778)
						)
						(arc
							(start -0.2794 0.1778)
							(mid -0.249642 0.249642)
							(end -0.1778 0.2794)
						)
						(arc
							(start 0.1778 0.2794)
							(mid 0.249642 0.249642)
							(end 0.2794 0.1778)
						)
						(arc
							(start 0.2794 -0.1778)
							(mid 0.249642 -0.249642)
							(end 0.1778 -0.2794)
						)
					)
					(width 0)
					(fill yes)
				)
			)
		)
	)
	(footprint ""
		(layer "F.Cu")
		(at 17.121632 -99.379786)
		(property "Reference" "TP9"
			(at 0 0 0)
			(layer "F.SilkS")
			(hide yes)
			(effects
				(font
					(size 1.27 1.27)
				)
			)
		)
		(property "Value" "TPAD32-GP"
			(at 0 -3.166364 0)
			(unlocked yes)
			(layer "F.Fab")
			(hide yes)
			(effects
				(font
					(size 1.016 1.016)
					(thickness 0.1524)
				)
			)
		)
		(property "Device Type" "TPAD32"
			(at 0 -4.690618 0)
			(unlocked yes)
			(layer "F.Fab")
			(hide yes)
			(effects
				(font
					(size 1.016 1.016)
					(thickness 0.1524)
				)
			)
		)
		(duplicate_pad_numbers_are_jumpers no)
		(fp_poly
			(pts
				(arc
					(start 0.4064 0)
					(mid -0.4064 0)
					(end 0.4064 0)
				)
			)
			(stroke
				(width 0)
				(type default)
			)
			(fill no)
			(layer "F.CrtYd")
		)
		(fp_poly
			(pts
				(arc
					(start 0.7112 0)
					(mid -0.7112 0)
					(end 0.7112 0)
				)
			)
			(stroke
				(width 0)
				(type default)
			)
			(fill no)
			(layer "F.Fab")
		)
		(pad "1" smd circle
			(at 0 0)
			(size 0.8128 0.8128)
			(layers "F.Cu" "F.Mask" "F.Paste")
			(net "I2C_C_BUF_READY")
		)
	)
	(footprint ""
		(layer "F.Cu")
		(at 120.116092 -47.354744 180)
		(property "Reference" "C355"
			(at 0 0 180)
			(layer "F.SilkS")
			(hide yes)
			(effects
				(font
					(size 1.27 1.27)
				)
			)
		)
		(property "Value" "SC10U25V5KX-GP"
			(at -0.0762 -6.1214 180)
			(unlocked yes)
			(layer "F.Fab")
			(hide yes)
			(effects
				(font
					(size 1.016 1.016)
					(thickness 0.1524)
				)
			)
		)
		(property "Device Type" "C805H56"
			(at -0.0762 -8.1534 180)
			(unlocked yes)
			(layer "F.Fab")
			(hide yes)
			(effects
				(font
					(size 1.016 1.016)
					(thickness 0.1524)
				)
			)
		)
		(duplicate_pad_numbers_are_jumpers no)
		(fp_line
			(start 0.635 0)
			(end -0.635 0)
			(stroke
				(width 0.508)
				(type default)
			)
			(layer "F.SilkS")
		)
		(fp_rect
			(start -0.9652 1.778)
			(end 0.9652 -1.778)
			(stroke
				(width 0)
				(type default)
			)
			(fill no)
			(layer "F.CrtYd")
		)
		(fp_poly
			(pts
				(xy -0.9652 -1.778) (xy 0.9652 -1.778) (xy 0.9652 1.778) (xy -0.9652 1.778)
			)
			(stroke
				(width 0)
				(type default)
			)
			(fill no)
			(layer "F.Fab")
		)
		(pad "1" smd rect
			(at 0 -0.9652 180)
			(size 1.397 1.143)
			(layers "F.Cu" "F.Mask" "F.Paste")
			(net "P12V")
		)
		(pad "2" smd rect
			(at 0 0.9652 180)
			(size 1.397 1.143)
			(layers "F.Cu" "F.Mask" "F.Paste")
			(net "GND")
		)
	)
	(footprint ""
		(layer "F.Cu")
		(at 10.492486 -98.872802 180)
		(property "Reference" "C345"
			(at 0 0 180)
			(layer "F.SilkS")
			(hide yes)
			(effects
				(font
					(size 1.27 1.27)
				)
			)
		)
		(property "Value" "SCD01U50V2KX-1GP"
			(at 1.1811 -2.7051 180)
			(unlocked yes)
			(layer "F.Fab")
			(hide yes)
			(effects
				(font
					(size 1.016 1.016)
					(thickness 0.1524)
				)
			)
		)
		(property "Device Type" "C402H22"
			(at 1.1811 -4.2291 180)
			(unlocked yes)
			(layer "F.Fab")
			(hide yes)
			(effects
				(font
					(size 1.016 1.016)
					(thickness 0.1524)
				)
			)
		)
		(duplicate_pad_numbers_are_jumpers no)
		(fp_rect
			(start -0.4318 0.9525)
			(end 0.4318 -0.9525)
			(stroke
				(width 0)
				(type default)
			)
			(fill no)
			(layer "F.CrtYd")
		)
		(fp_rect
			(start -0.4318 0.9525)
			(end 0.4318 -0.9525)
			(stroke
				(width 0)
				(type default)
			)
			(fill no)
			(layer "F.Fab")
		)
		(pad "1" smd custom
			(at 0 -0.4445 180)
			(size 0.1524 0.1524)
			(layers "F.Cu" "F.Mask" "F.Paste")
			(net "P3V3")
			(options
				(clearance outline)
				(anchor circle)
			)
			(primitives
				(gr_poly
					(pts
						(arc
							(start 0.3048 -0.2032)
							(mid 0.275042 -0.275042)
							(end 0.2032 -0.3048)
						)
						(arc
							(start -0.2032 -0.3048)
							(mid -0.275042 -0.275042)
							(end -0.3048 -0.2032)
						)
						(arc
							(start -0.3048 0.2032)
							(mid -0.275042 0.275042)
							(end -0.2032 0.3048)
						)
						(arc
							(start 0.2032 0.3048)
							(mid 0.275042 0.275042)
							(end 0.3048 0.2032)
						)
					)
					(width 0)
					(fill yes)
				)
			)
		)
		(pad "2" smd custom
			(at 0 0.4445 180)
			(size 0.1524 0.1524)
			(layers "F.Cu" "F.Mask" "F.Paste")
			(net "GND")
			(options
				(clearance outline)
				(anchor circle)
			)
			(primitives
				(gr_poly
					(pts
						(arc
							(start 0.3048 -0.2032)
							(mid 0.275042 -0.275042)
							(end 0.2032 -0.3048)
						)
						(arc
							(start -0.2032 -0.3048)
							(mid -0.275042 -0.275042)
							(end -0.3048 -0.2032)
						)
						(arc
							(start -0.3048 0.2032)
							(mid -0.275042 0.275042)
							(end -0.2032 0.3048)
						)
						(arc
							(start 0.2032 0.3048)
							(mid 0.275042 0.275042)
							(end 0.3048 0.2032)
						)
					)
					(width 0)
					(fill yes)
				)
			)
		)
	)
)
